(kicad_sch
	(version 20250114)
	(generator "eeschema")
	(generator_version "9.0")
	(paper "A3")
	(title_block
		(title "PolarFire SoM")
		(date "2025-07-22")
		(rev "1.1.4")
		(company "Antmicro Ltd")
		(comment 1 "www.antmicro.com")
	)
	(text "REF CLK\n\n"
		(exclude_from_sim no)
		(at 86.36 210.82 0)
		(effects
			(font
				(size 4 4)
				(thickness 0.8)
				(bold yes)
			)
			(justify left bottom)
		)
	)
	(text "PolarFire XCVR"
		(exclude_from_sim no)
		(at 15.24 21.59 0)
		(effects
			(font
				(size 4 4)
				(thickness 0.8)
				(bold yes)
			)
			(justify left bottom)
		)
	)
	(junction
		(at 55.88 231.14)
		(diameter 0)
		(color 0 0 0 0)
	)
	(junction
		(at 105.41 232.41)
		(diameter 0)
		(color 0 0 0 0)
	)
	(junction
		(at 55.88 220.98)
		(diameter 0)
		(color 0 0 0 0)
	)
	(junction
		(at 106.68 241.3)
		(diameter 0)
		(color 0 0 0 0)
	)
	(junction
		(at 64.77 220.98)
		(diameter 0)
		(color 0 0 0 0)
	)
	(junction
		(at 64.77 231.14)
		(diameter 0)
		(color 0 0 0 0)
	)
	(junction
		(at 73.66 223.52)
		(diameter 0)
		(color 0 0 0 0)
	)
	(junction
		(at 107.95 229.87)
		(diameter 0)
		(color 0 0 0 0)
	)
	(junction
		(at 73.66 220.98)
		(diameter 0)
		(color 0 0 0 0)
	)
	(junction
		(at 73.66 231.14)
		(diameter 0)
		(color 0 0 0 0)
	)
	(no_connect
		(at 187.96 154.94)
	)
	(no_connect
		(at 187.96 152.4)
	)
	(no_connect
		(at 238.76 144.78)
	)
	(no_connect
		(at 238.76 147.32)
	)
	(bus_entry
		(at 144.78 114.3)
		(size -2.54 -2.54)
		(stroke
			(width 0)
			(type default)
		)
	)
	(bus_entry
		(at 144.78 132.08)
		(size -2.54 -2.54)
		(stroke
			(width 0)
			(type default)
		)
	)
	(bus_entry
		(at 252.73 114.3)
		(size 2.54 -2.54)
		(stroke
			(width 0)
			(type default)
		)
	)
	(bus_entry
		(at 144.78 137.16)
		(size -2.54 -2.54)
		(stroke
			(width 0)
			(type default)
		)
	)
	(bus_entry
		(at 144.78 116.84)
		(size -2.54 -2.54)
		(stroke
			(width 0)
			(type default)
		)
	)
	(bus_entry
		(at 252.73 124.46)
		(size 2.54 -2.54)
		(stroke
			(width 0)
			(type default)
		)
	)
	(bus_entry
		(at 144.78 139.7)
		(size -2.54 -2.54)
		(stroke
			(width 0)
			(type default)
		)
	)
	(bus_entry
		(at 252.73 121.92)
		(size 2.54 -2.54)
		(stroke
			(width 0)
			(type default)
		)
	)
	(bus_entry
		(at 138.43 229.87)
		(size 2.54 -2.54)
		(stroke
			(width 0)
			(type default)
		)
	)
	(bus_entry
		(at 252.73 116.84)
		(size 2.54 -2.54)
		(stroke
			(width 0)
			(type default)
		)
	)
	(bus_entry
		(at 252.73 129.54)
		(size 2.54 -2.54)
		(stroke
			(width 0)
			(type default)
		)
	)
	(bus_entry
		(at 252.73 132.08)
		(size 2.54 -2.54)
		(stroke
			(width 0)
			(type default)
		)
	)
	(bus_entry
		(at 144.78 124.46)
		(size -2.54 -2.54)
		(stroke
			(width 0)
			(type default)
		)
	)
	(bus_entry
		(at 138.43 232.41)
		(size 2.54 -2.54)
		(stroke
			(width 0)
			(type default)
		)
	)
	(bus_entry
		(at 144.78 129.54)
		(size -2.54 -2.54)
		(stroke
			(width 0)
			(type default)
		)
	)
	(bus_entry
		(at 144.78 121.92)
		(size -2.54 -2.54)
		(stroke
			(width 0)
			(type default)
		)
	)
	(bus_entry
		(at 252.73 137.16)
		(size 2.54 -2.54)
		(stroke
			(width 0)
			(type default)
		)
	)
	(bus_entry
		(at 252.73 139.7)
		(size 2.54 -2.54)
		(stroke
			(width 0)
			(type default)
		)
	)
	(wire
		(pts
			(xy 160.02 130.81) (xy 161.29 130.81)
		)
		(stroke
			(width 0)
			(type default)
		)
	)
	(wire
		(pts
			(xy 238.76 121.92) (xy 252.73 121.92)
		)
		(stroke
			(width 0)
			(type default)
		)
	)
	(wire
		(pts
			(xy 55.88 219.71) (xy 55.88 220.98)
		)
		(stroke
			(width 0)
			(type default)
		)
	)
	(wire
		(pts
			(xy 107.95 240.03) (xy 107.95 241.3)
		)
		(stroke
			(width 0)
			(type default)
		)
	)
	(wire
		(pts
			(xy 105.41 232.41) (xy 105.41 234.95)
		)
		(stroke
			(width 0)
			(type default)
		)
	)
	(bus
		(pts
			(xy 142.24 119.38) (xy 142.24 121.92)
		)
		(stroke
			(width 0)
			(type default)
		)
	)
	(wire
		(pts
			(xy 185.42 133.35) (xy 185.42 132.08)
		)
		(stroke
			(width 0)
			(type default)
		)
	)
	(wire
		(pts
			(xy 170.18 120.65) (xy 185.42 120.65)
		)
		(stroke
			(width 0)
			(type default)
		)
	)
	(wire
		(pts
			(xy 74.93 227.33) (xy 73.66 227.33)
		)
		(stroke
			(width 0)
			(type default)
		)
	)
	(wire
		(pts
			(xy 144.78 137.16) (xy 158.75 137.16)
		)
		(stroke
			(width 0)
			(type default)
		)
	)
	(wire
		(pts
			(xy 144.78 124.46) (xy 160.02 124.46)
		)
		(stroke
			(width 0)
			(type default)
		)
	)
	(wire
		(pts
			(xy 55.88 220.98) (xy 55.88 222.25)
		)
		(stroke
			(width 0)
			(type default)
		)
	)
	(wire
		(pts
			(xy 185.42 137.16) (xy 185.42 135.89)
		)
		(stroke
			(width 0)
			(type default)
		)
	)
	(bus
		(pts
			(xy 255.27 127) (xy 255.27 129.54)
		)
		(stroke
			(width 0)
			(type default)
		)
	)
	(wire
		(pts
			(xy 170.18 135.89) (xy 185.42 135.89)
		)
		(stroke
			(width 0)
			(type default)
		)
	)
	(wire
		(pts
			(xy 184.15 129.54) (xy 187.96 129.54)
		)
		(stroke
			(width 0)
			(type default)
		)
	)
	(wire
		(pts
			(xy 55.88 220.98) (xy 64.77 220.98)
		)
		(stroke
			(width 0)
			(type default)
		)
	)
	(wire
		(pts
			(xy 160.02 124.46) (xy 160.02 123.19)
		)
		(stroke
			(width 0)
			(type default)
		)
	)
	(wire
		(pts
			(xy 158.75 118.11) (xy 158.75 116.84)
		)
		(stroke
			(width 0)
			(type default)
		)
	)
	(wire
		(pts
			(xy 184.15 138.43) (xy 170.18 138.43)
		)
		(stroke
			(width 0)
			(type default)
		)
	)
	(wire
		(pts
			(xy 185.42 121.92) (xy 185.42 120.65)
		)
		(stroke
			(width 0)
			(type default)
		)
	)
	(bus
		(pts
			(xy 142.24 114.3) (xy 142.24 119.38)
		)
		(stroke
			(width 0)
			(type default)
		)
	)
	(wire
		(pts
			(xy 106.68 241.3) (xy 107.95 241.3)
		)
		(stroke
			(width 0)
			(type default)
		)
	)
	(wire
		(pts
			(xy 106.68 241.3) (xy 105.41 241.3)
		)
		(stroke
			(width 0)
			(type default)
		)
	)
	(wire
		(pts
			(xy 73.66 223.52) (xy 73.66 227.33)
		)
		(stroke
			(width 0)
			(type default)
		)
	)
	(wire
		(pts
			(xy 184.15 124.46) (xy 184.15 123.19)
		)
		(stroke
			(width 0)
			(type default)
		)
	)
	(bus
		(pts
			(xy 140.97 226.06) (xy 140.97 227.33)
		)
		(stroke
			(width 0)
			(type default)
		)
	)
	(wire
		(pts
			(xy 160.02 130.81) (xy 160.02 129.54)
		)
		(stroke
			(width 0)
			(type default)
		)
	)
	(bus
		(pts
			(xy 142.24 134.62) (xy 142.24 137.16)
		)
		(stroke
			(width 0)
			(type default)
		)
	)
	(wire
		(pts
			(xy 160.02 138.43) (xy 161.29 138.43)
		)
		(stroke
			(width 0)
			(type default)
		)
	)
	(wire
		(pts
			(xy 144.78 139.7) (xy 160.02 139.7)
		)
		(stroke
			(width 0)
			(type default)
		)
	)
	(wire
		(pts
			(xy 238.76 137.16) (xy 252.73 137.16)
		)
		(stroke
			(width 0)
			(type default)
		)
	)
	(wire
		(pts
			(xy 238.76 116.84) (xy 252.73 116.84)
		)
		(stroke
			(width 0)
			(type default)
		)
	)
	(wire
		(pts
			(xy 144.78 114.3) (xy 160.02 114.3)
		)
		(stroke
			(width 0)
			(type default)
		)
	)
	(wire
		(pts
			(xy 101.6 224.79) (xy 120.65 224.79)
		)
		(stroke
			(width 0)
			(type default)
		)
	)
	(bus
		(pts
			(xy 255.27 134.62) (xy 255.27 137.16)
		)
		(stroke
			(width 0)
			(type default)
		)
	)
	(bus
		(pts
			(xy 142.24 127) (xy 142.24 129.54)
		)
		(stroke
			(width 0)
			(type default)
		)
	)
	(wire
		(pts
			(xy 185.42 132.08) (xy 187.96 132.08)
		)
		(stroke
			(width 0)
			(type default)
		)
	)
	(wire
		(pts
			(xy 160.02 123.19) (xy 161.29 123.19)
		)
		(stroke
			(width 0)
			(type default)
		)
	)
	(bus
		(pts
			(xy 255.27 121.92) (xy 255.27 127)
		)
		(stroke
			(width 0)
			(type default)
		)
	)
	(wire
		(pts
			(xy 101.6 229.87) (xy 107.95 229.87)
		)
		(stroke
			(width 0)
			(type default)
		)
	)
	(wire
		(pts
			(xy 101.6 232.41) (xy 105.41 232.41)
		)
		(stroke
			(width 0)
			(type default)
		)
	)
	(bus
		(pts
			(xy 255.27 111.76) (xy 256.54 110.49)
		)
		(stroke
			(width 0)
			(type default)
		)
	)
	(wire
		(pts
			(xy 238.76 114.3) (xy 252.73 114.3)
		)
		(stroke
			(width 0)
			(type default)
		)
	)
	(wire
		(pts
			(xy 170.18 118.11) (xy 185.42 118.11)
		)
		(stroke
			(width 0)
			(type default)
		)
	)
	(wire
		(pts
			(xy 64.77 220.98) (xy 64.77 222.25)
		)
		(stroke
			(width 0)
			(type default)
		)
	)
	(wire
		(pts
			(xy 144.78 116.84) (xy 158.75 116.84)
		)
		(stroke
			(width 0)
			(type default)
		)
	)
	(wire
		(pts
			(xy 64.77 231.14) (xy 73.66 231.14)
		)
		(stroke
			(width 0)
			(type default)
		)
	)
	(bus
		(pts
			(xy 255.27 114.3) (xy 255.27 119.38)
		)
		(stroke
			(width 0)
			(type default)
		)
	)
	(wire
		(pts
			(xy 144.78 129.54) (xy 160.02 129.54)
		)
		(stroke
			(width 0)
			(type default)
		)
	)
	(wire
		(pts
			(xy 158.75 133.35) (xy 161.29 133.35)
		)
		(stroke
			(width 0)
			(type default)
		)
	)
	(wire
		(pts
			(xy 73.66 220.98) (xy 74.93 220.98)
		)
		(stroke
			(width 0)
			(type default)
		)
	)
	(wire
		(pts
			(xy 187.96 139.7) (xy 184.15 139.7)
		)
		(stroke
			(width 0)
			(type default)
		)
	)
	(wire
		(pts
			(xy 160.02 139.7) (xy 160.02 138.43)
		)
		(stroke
			(width 0)
			(type default)
		)
	)
	(wire
		(pts
			(xy 158.75 135.89) (xy 161.29 135.89)
		)
		(stroke
			(width 0)
			(type default)
		)
	)
	(wire
		(pts
			(xy 120.65 229.87) (xy 138.43 229.87)
		)
		(stroke
			(width 0)
			(type default)
		)
	)
	(wire
		(pts
			(xy 184.15 123.19) (xy 170.18 123.19)
		)
		(stroke
			(width 0)
			(type default)
		)
	)
	(wire
		(pts
			(xy 158.75 120.65) (xy 161.29 120.65)
		)
		(stroke
			(width 0)
			(type default)
		)
	)
	(wire
		(pts
			(xy 158.75 137.16) (xy 158.75 135.89)
		)
		(stroke
			(width 0)
			(type default)
		)
	)
	(wire
		(pts
			(xy 55.88 227.33) (xy 55.88 231.14)
		)
		(stroke
			(width 0)
			(type default)
		)
	)
	(wire
		(pts
			(xy 185.42 116.84) (xy 187.96 116.84)
		)
		(stroke
			(width 0)
			(type default)
		)
	)
	(wire
		(pts
			(xy 170.18 130.81) (xy 184.15 130.81)
		)
		(stroke
			(width 0)
			(type default)
		)
	)
	(wire
		(pts
			(xy 105.41 232.41) (xy 113.03 232.41)
		)
		(stroke
			(width 0)
			(type default)
		)
	)
	(wire
		(pts
			(xy 170.18 115.57) (xy 184.15 115.57)
		)
		(stroke
			(width 0)
			(type default)
		)
	)
	(wire
		(pts
			(xy 105.41 240.03) (xy 105.41 241.3)
		)
		(stroke
			(width 0)
			(type default)
		)
	)
	(wire
		(pts
			(xy 158.75 121.92) (xy 158.75 120.65)
		)
		(stroke
			(width 0)
			(type default)
		)
	)
	(wire
		(pts
			(xy 144.78 121.92) (xy 158.75 121.92)
		)
		(stroke
			(width 0)
			(type default)
		)
	)
	(wire
		(pts
			(xy 106.68 242.57) (xy 106.68 241.3)
		)
		(stroke
			(width 0)
			(type default)
		)
	)
	(bus
		(pts
			(xy 257.81 110.49) (xy 256.54 110.49)
		)
		(stroke
			(width 0)
			(type default)
		)
	)
	(wire
		(pts
			(xy 74.93 223.52) (xy 73.66 223.52)
		)
		(stroke
			(width 0)
			(type default)
		)
	)
	(bus
		(pts
			(xy 142.24 224.79) (xy 143.51 224.79)
		)
		(stroke
			(width 0)
			(type default)
		)
	)
	(wire
		(pts
			(xy 187.96 144.78) (xy 168.91 144.78)
		)
		(stroke
			(width 0)
			(type default)
		)
	)
	(wire
		(pts
			(xy 158.75 118.11) (xy 161.29 118.11)
		)
		(stroke
			(width 0)
			(type default)
		)
	)
	(wire
		(pts
			(xy 64.77 220.98) (xy 73.66 220.98)
		)
		(stroke
			(width 0)
			(type default)
		)
	)
	(wire
		(pts
			(xy 107.95 229.87) (xy 115.57 229.87)
		)
		(stroke
			(width 0)
			(type default)
		)
	)
	(wire
		(pts
			(xy 187.96 147.32) (xy 168.91 147.32)
		)
		(stroke
			(width 0)
			(type default)
		)
	)
	(wire
		(pts
			(xy 64.77 227.33) (xy 64.77 231.14)
		)
		(stroke
			(width 0)
			(type default)
		)
	)
	(wire
		(pts
			(xy 184.15 115.57) (xy 184.15 114.3)
		)
		(stroke
			(width 0)
			(type default)
		)
	)
	(wire
		(pts
			(xy 73.66 233.68) (xy 73.66 231.14)
		)
		(stroke
			(width 0)
			(type default)
		)
	)
	(bus
		(pts
			(xy 140.97 109.22) (xy 142.24 110.49)
		)
		(stroke
			(width 0)
			(type default)
		)
	)
	(wire
		(pts
			(xy 185.42 118.11) (xy 185.42 116.84)
		)
		(stroke
			(width 0)
			(type default)
		)
	)
	(wire
		(pts
			(xy 238.76 139.7) (xy 252.73 139.7)
		)
		(stroke
			(width 0)
			(type default)
		)
	)
	(wire
		(pts
			(xy 160.02 115.57) (xy 161.29 115.57)
		)
		(stroke
			(width 0)
			(type default)
		)
	)
	(bus
		(pts
			(xy 140.97 227.33) (xy 140.97 229.87)
		)
		(stroke
			(width 0)
			(type default)
		)
	)
	(bus
		(pts
			(xy 142.24 111.76) (xy 142.24 114.3)
		)
		(stroke
			(width 0)
			(type default)
		)
	)
	(wire
		(pts
			(xy 187.96 124.46) (xy 184.15 124.46)
		)
		(stroke
			(width 0)
			(type default)
		)
	)
	(wire
		(pts
			(xy 170.18 133.35) (xy 185.42 133.35)
		)
		(stroke
			(width 0)
			(type default)
		)
	)
	(bus
		(pts
			(xy 255.27 119.38) (xy 255.27 121.92)
		)
		(stroke
			(width 0)
			(type default)
		)
	)
	(wire
		(pts
			(xy 74.93 233.68) (xy 73.66 233.68)
		)
		(stroke
			(width 0)
			(type default)
		)
	)
	(wire
		(pts
			(xy 184.15 139.7) (xy 184.15 138.43)
		)
		(stroke
			(width 0)
			(type default)
		)
	)
	(wire
		(pts
			(xy 184.15 130.81) (xy 184.15 129.54)
		)
		(stroke
			(width 0)
			(type default)
		)
	)
	(wire
		(pts
			(xy 73.66 223.52) (xy 73.66 220.98)
		)
		(stroke
			(width 0)
			(type default)
		)
	)
	(wire
		(pts
			(xy 73.66 231.14) (xy 74.93 231.14)
		)
		(stroke
			(width 0)
			(type default)
		)
	)
	(wire
		(pts
			(xy 144.78 132.08) (xy 158.75 132.08)
		)
		(stroke
			(width 0)
			(type default)
		)
	)
	(bus
		(pts
			(xy 142.24 110.49) (xy 142.24 111.76)
		)
		(stroke
			(width 0)
			(type default)
		)
	)
	(bus
		(pts
			(xy 142.24 129.54) (xy 142.24 134.62)
		)
		(stroke
			(width 0)
			(type default)
		)
	)
	(bus
		(pts
			(xy 255.27 111.76) (xy 255.27 114.3)
		)
		(stroke
			(width 0)
			(type default)
		)
	)
	(wire
		(pts
			(xy 55.88 231.14) (xy 55.88 232.41)
		)
		(stroke
			(width 0)
			(type default)
		)
	)
	(bus
		(pts
			(xy 255.27 129.54) (xy 255.27 134.62)
		)
		(stroke
			(width 0)
			(type default)
		)
	)
	(wire
		(pts
			(xy 107.95 229.87) (xy 107.95 234.95)
		)
		(stroke
			(width 0)
			(type default)
		)
	)
	(wire
		(pts
			(xy 101.6 222.25) (xy 120.65 222.25)
		)
		(stroke
			(width 0)
			(type default)
		)
	)
	(wire
		(pts
			(xy 187.96 137.16) (xy 185.42 137.16)
		)
		(stroke
			(width 0)
			(type default)
		)
	)
	(wire
		(pts
			(xy 118.11 232.41) (xy 138.43 232.41)
		)
		(stroke
			(width 0)
			(type default)
		)
	)
	(wire
		(pts
			(xy 187.96 121.92) (xy 185.42 121.92)
		)
		(stroke
			(width 0)
			(type default)
		)
	)
	(wire
		(pts
			(xy 238.76 129.54) (xy 252.73 129.54)
		)
		(stroke
			(width 0)
			(type default)
		)
	)
	(wire
		(pts
			(xy 55.88 231.14) (xy 64.77 231.14)
		)
		(stroke
			(width 0)
			(type default)
		)
	)
	(bus
		(pts
			(xy 139.7 109.22) (xy 140.97 109.22)
		)
		(stroke
			(width 0)
			(type default)
		)
	)
	(wire
		(pts
			(xy 158.75 133.35) (xy 158.75 132.08)
		)
		(stroke
			(width 0)
			(type default)
		)
	)
	(wire
		(pts
			(xy 238.76 124.46) (xy 252.73 124.46)
		)
		(stroke
			(width 0)
			(type default)
		)
	)
	(bus
		(pts
			(xy 142.24 121.92) (xy 142.24 127)
		)
		(stroke
			(width 0)
			(type default)
		)
	)
	(wire
		(pts
			(xy 160.02 115.57) (xy 160.02 114.3)
		)
		(stroke
			(width 0)
			(type default)
		)
	)
	(bus
		(pts
			(xy 140.97 226.06) (xy 142.24 224.79)
		)
		(stroke
			(width 0)
			(type default)
		)
	)
	(wire
		(pts
			(xy 184.15 114.3) (xy 187.96 114.3)
		)
		(stroke
			(width 0)
			(type default)
		)
	)
	(wire
		(pts
			(xy 238.76 132.08) (xy 252.73 132.08)
		)
		(stroke
			(width 0)
			(type default)
		)
	)
	(label "PCIE.TXD1_N"
		(at 144.78 124.46 0)
		(effects
			(font
				(size 1.27 1.27)
			)
			(justify left bottom)
		)
	)
	(label "PCIE.TXD1_P"
		(at 144.78 121.92 0)
		(effects
			(font
				(size 1.27 1.27)
			)
			(justify left bottom)
		)
	)
	(label "PCIE.TXD3_P"
		(at 144.78 137.16 0)
		(effects
			(font
				(size 1.27 1.27)
			)
			(justify left bottom)
		)
	)
	(label "PCIE.TXD2_N"
		(at 144.78 132.08 0)
		(effects
			(font
				(size 1.27 1.27)
			)
			(justify left bottom)
		)
	)
	(label "XCVR_TX0_P"
		(at 171.45 115.57 0)
		(effects
			(font
				(size 1.27 1.27)
			)
			(justify left bottom)
		)
	)
	(label "PCIE.RXD3_P"
		(at 252.73 137.16 180)
		(effects
			(font
				(size 1.27 1.27)
			)
			(justify right bottom)
		)
	)
	(label "PCIE.RXD1_N"
		(at 252.73 124.46 180)
		(effects
			(font
				(size 1.27 1.27)
			)
			(justify right bottom)
		)
	)
	(label "PCIE.TXD0_N"
		(at 144.78 116.84 0)
		(effects
			(font
				(size 1.27 1.27)
			)
			(justify left bottom)
		)
	)
	(label "PCIE.TXD2_P"
		(at 144.78 129.54 0)
		(effects
			(font
				(size 1.27 1.27)
			)
			(justify left bottom)
		)
	)
	(label "XCVR_TX2_N"
		(at 171.45 133.35 0)
		(effects
			(font
				(size 1.27 1.27)
			)
			(justify left bottom)
		)
	)
	(label "PF_PCIe_CLK_N"
		(at 120.65 224.79 180)
		(effects
			(font
				(size 1.27 1.27)
			)
			(justify right bottom)
		)
	)
	(label "PF_PCIe_CLK_P"
		(at 168.91 144.78 0)
		(effects
			(font
				(size 1.27 1.27)
			)
			(justify left bottom)
		)
	)
	(label "PCIE.TXD3_N"
		(at 144.78 139.7 0)
		(effects
			(font
				(size 1.27 1.27)
			)
			(justify left bottom)
		)
	)
	(label "PCIE.RXD2_P"
		(at 252.73 129.54 180)
		(effects
			(font
				(size 1.27 1.27)
			)
			(justify right bottom)
		)
	)
	(label "PCIE.RXD2_N"
		(at 252.73 132.08 180)
		(effects
			(font
				(size 1.27 1.27)
			)
			(justify right bottom)
		)
	)
	(label "XCVR_TX1_P"
		(at 171.45 120.65 0)
		(effects
			(font
				(size 1.27 1.27)
			)
			(justify left bottom)
		)
	)
	(label "PCIE.CLK_P"
		(at 138.43 229.87 180)
		(effects
			(font
				(size 1.27 1.27)
			)
			(justify right bottom)
		)
	)
	(label "XCVR_TX0_N"
		(at 171.3962 118.11 0)
		(effects
			(font
				(size 1.27 1.27)
			)
			(justify left bottom)
		)
	)
	(label "PF_PCIe_CLK_P"
		(at 120.65 222.25 180)
		(effects
			(font
				(size 1.27 1.27)
			)
			(justify right bottom)
		)
	)
	(label "XCVR_TX2_P"
		(at 171.5038 130.81 0)
		(effects
			(font
				(size 1.27 1.27)
			)
			(justify left bottom)
		)
	)
	(label "XCVR_TX3_N"
		(at 171.5038 138.43 0)
		(effects
			(font
				(size 1.27 1.27)
			)
			(justify left bottom)
		)
	)
	(label "PCIE.CLK_N"
		(at 137.795 232.41 180)
		(effects
			(font
				(size 1.27 1.27)
			)
			(justify right bottom)
		)
	)
	(label "PCIE.TXD0_P"
		(at 144.78 114.3 0)
		(effects
			(font
				(size 1.27 1.27)
			)
			(justify left bottom)
		)
	)
	(label "PF_PCIe_CLK_N"
		(at 168.91 147.32 0)
		(effects
			(font
				(size 1.27 1.27)
			)
			(justify left bottom)
		)
	)
	(label "XCVR_TX1_N"
		(at 171.45 123.19 0)
		(effects
			(font
				(size 1.27 1.27)
			)
			(justify left bottom)
		)
	)
	(label "XCVR_TX3_P"
		(at 171.5038 135.89 0)
		(effects
			(font
				(size 1.27 1.27)
			)
			(justify left bottom)
		)
	)
	(label "PCIE.RXD3_N"
		(at 252.73 139.7 180)
		(effects
			(font
				(size 1.27 1.27)
			)
			(justify right bottom)
		)
	)
	(label "PCIE.RXD0_P"
		(at 252.73 114.3 180)
		(effects
			(font
				(size 1.27 1.27)
			)
			(justify right bottom)
		)
	)
	(label "PCIE.RXD0_N"
		(at 252.73 116.84 180)
		(effects
			(font
				(size 1.27 1.27)
			)
			(justify right bottom)
		)
	)
	(label "PCIE.RXD1_P"
		(at 252.73 121.92 180)
		(effects
			(font
				(size 1.27 1.27)
			)
			(justify right bottom)
		)
	)
	(hierarchical_label "PCIE{PCIe_x4}"
		(shape bidirectional)
		(at 257.81 110.49 0)
		(effects
			(font
				(size 1.27 1.27)
			)
			(justify left)
		)
	)
	(hierarchical_label "PCIE{PCIe_x4}"
		(shape bidirectional)
		(at 143.51 224.79 0)
		(effects
			(font
				(size 1.27 1.27)
			)
			(justify left)
		)
	)
	(hierarchical_label "PCIE{PCIe_x4}"
		(shape bidirectional)
		(at 139.7 109.22 180)
		(effects
			(font
				(size 1.27 1.27)
			)
			(justify right)
		)
	)
	(symbol
		(lib_id "antmicroCapacitors0402:C_100n_0402")
		(at 64.77 227.33 90)
		(unit 1)
		(exclude_from_sim no)
		(in_bom yes)
		(on_board yes)
		(dnp no)
		(property "Reference" "C12"
			(at 67.31 223.52 90)
			(effects
				(font
					(size 1.27 1.27)
					(thickness 0.15)
				)
				(justify right)
			)
		)
		(property "Value" "C_100n_0402"
			(at 74.93 207.01 0)
			(effects
				(font
					(size 1.27 1.27)
					(thickness 0.15)
				)
				(justify left bottom)
				(hide yes)
			)
		)
		(property "Footprint" "antmicro-footprints:C_0402_1005Metric"
			(at 77.47 207.01 0)
			(effects
				(font
					(size 1.27 1.27)
					(thickness 0.15)
				)
				(justify left bottom)
				(hide yes)
			)
		)
		(property "Datasheet" "https://www.murata.com/products/productdetail?partno=GRM155R61H104KE14%23"
			(at 80.01 207.01 0)
			(effects
				(font
					(size 1.27 1.27)
					(thickness 0.15)
				)
				(justify left bottom)
				(hide yes)
			)
		)
		(property "Description" "SMD Multilayer Ceramic Capacitor, 0.1 µF, 50 V, 0402 [1005 Metric], ± 10%, X5R, GRM Series"
			(at 64.77 227.33 0)
			(effects
				(font
					(size 1.27 1.27)
				)
				(hide yes)
			)
		)
		(property "MPN" "GRM155R61H104KE14D"
			(at 82.55 207.01 0)
			(effects
				(font
					(size 1.27 1.27)
					(thickness 0.15)
				)
				(justify left bottom)
				(hide yes)
			)
		)
		(property "Manufacturer" "Murata"
			(at 85.09 207.01 0)
			(effects
				(font
					(size 1.27 1.27)
					(thickness 0.15)
				)
				(justify left bottom)
				(hide yes)
			)
		)
		(property "License" "Apache-2.0"
			(at 87.63 207.01 0)
			(effects
				(font
					(size 1.27 1.27)
					(thickness 0.15)
				)
				(justify left bottom)
				(hide yes)
			)
		)
		(property "Author" "Antmicro"
			(at 90.17 207.01 0)
			(effects
				(font
					(size 1.27 1.27)
					(thickness 0.15)
				)
				(justify left bottom)
				(hide yes)
			)
		)
		(property "Val" "100n"
			(at 72.39 226.06 90)
			(effects
				(font
					(size 1.27 1.27)
					(thickness 0.15)
				)
				(justify left bottom)
			)
		)
		(property "Voltage" "50V"
			(at 92.71 207.01 0)
			(effects
				(font
					(size 1.27 1.27)
				)
				(justify left bottom)
				(hide yes)
			)
		)
		(property "Dielectric" "X5R"
			(at 95.25 207.01 0)
			(effects
				(font
					(size 1.27 1.27)
				)
				(justify left bottom)
				(hide yes)
			)
		)
		(property "Public" ""
			(at 97.79 207.01 0)
			(effects
				(font
					(size 1.27 1.27)
				)
				(justify left bottom)
				(hide yes)
			)
		)
		(pin "1"
		)
		(pin "2"
		)
		(instances
			(project "polarfire-som"
				(path ""
					(reference "C12")
					(unit 1)
				)
			)
		)
	)
	(symbol
		(lib_id "antmicropower:+2V5")
		(at 55.88 219.71 0)
		(unit 1)
		(exclude_from_sim no)
		(in_bom yes)
		(on_board yes)
		(dnp no)
		(property "Reference" "#PWR0166"
			(at 55.88 223.52 0)
			(effects
				(font
					(size 1.27 1.27)
				)
				(hide yes)
			)
		)
		(property "Value" "+2V5"
			(at 55.88 215.9 0)
			(effects
				(font
					(size 1.27 1.27)
				)
			)
		)
		(property "Footprint" ""
			(at 55.88 219.71 0)
			(effects
				(font
					(size 1.27 1.27)
				)
				(hide yes)
			)
		)
		(property "Datasheet" ""
			(at 55.88 219.71 0)
			(effects
				(font
					(size 1.27 1.27)
				)
				(hide yes)
			)
		)
		(property "Description" ""
			(at 55.88 219.71 0)
			(effects
				(font
					(size 1.27 1.27)
				)
				(hide yes)
			)
		)
		(pin "1"
		)
		(instances
			(project "polarfire-som"
				(path ""
					(reference "#PWR0166")
					(unit 1)
				)
			)
		)
	)
	(symbol
		(lib_id "antmicropower:GND")
		(at 106.68 242.57 0)
		(unit 1)
		(exclude_from_sim no)
		(in_bom yes)
		(on_board yes)
		(dnp no)
		(property "Reference" "#PWR0306"
			(at 115.57 245.11 0)
			(effects
				(font
					(size 1.27 1.27)
					(thickness 0.15)
				)
				(justify left bottom)
				(hide yes)
			)
		)
		(property "Value" "GND"
			(at 106.68 246.38 0)
			(effects
				(font
					(size 1.27 1.27)
					(thickness 0.15)
				)
			)
		)
		(property "Footprint" ""
			(at 115.57 250.19 0)
			(effects
				(font
					(size 1.27 1.27)
					(thickness 0.15)
				)
				(justify left bottom)
				(hide yes)
			)
		)
		(property "Datasheet" ""
			(at 115.57 255.27 0)
			(effects
				(font
					(size 1.27 1.27)
					(thickness 0.15)
				)
				(justify left bottom)
				(hide yes)
			)
		)
		(property "Description" ""
			(at 106.68 242.57 0)
			(effects
				(font
					(size 1.27 1.27)
				)
				(hide yes)
			)
		)
		(property "Author" "Antmicro"
			(at 115.57 250.19 0)
			(effects
				(font
					(size 1.27 1.27)
					(thickness 0.15)
				)
				(justify left bottom)
				(hide yes)
			)
		)
		(property "License" "Apache-2.0"
			(at 115.57 252.73 0)
			(effects
				(font
					(size 1.27 1.27)
					(thickness 0.15)
				)
				(justify left bottom)
				(hide yes)
			)
		)
		(pin "1"
		)
		(instances
			(project "polarfire-som"
				(path ""
					(reference "#PWR0306")
					(unit 1)
				)
			)
		)
	)
	(symbol
		(lib_id "antmicroResistors0402:R_50R_0402")
		(at 105.41 240.03 270)
		(mirror x)
		(unit 1)
		(exclude_from_sim no)
		(in_bom yes)
		(on_board yes)
		(dnp no)
		(property "Reference" "R88"
			(at 104.14 236.22 90)
			(effects
				(font
					(size 1.27 1.27)
					(thickness 0.15)
				)
				(justify right)
			)
		)
		(property "Value" "R_50R_0402"
			(at 92.71 219.71 0)
			(effects
				(font
					(size 1.27 1.27)
					(thickness 0.15)
				)
				(justify left bottom)
				(hide yes)
			)
		)
		(property "Footprint" "antmicro-footprints:R_0402_1005Metric"
			(at 90.17 219.71 0)
			(effects
				(font
					(size 1.27 1.27)
					(thickness 0.15)
				)
				(justify left bottom)
				(hide yes)
			)
		)
		(property "Datasheet" "https://www.bourns.com/docs/product-datasheets/cr.pdf"
			(at 87.63 219.71 0)
			(effects
				(font
					(size 1.27 1.27)
					(thickness 0.15)
				)
				(justify left bottom)
				(hide yes)
			)
		)
		(property "Description" "SMD Chip Resistor"
			(at 105.41 240.03 0)
			(effects
				(font
					(size 1.27 1.27)
				)
				(hide yes)
			)
		)
		(property "MPN" "CR0402-FX-50R0GLF"
			(at 85.09 219.71 0)
			(effects
				(font
					(size 1.27 1.27)
					(thickness 0.15)
				)
				(justify left bottom)
				(hide yes)
			)
		)
		(property "Manufacturer" "Bourns"
			(at 82.55 219.71 0)
			(effects
				(font
					(size 1.27 1.27)
					(thickness 0.15)
				)
				(justify left bottom)
				(hide yes)
			)
		)
		(property "License" "Apache-2.0"
			(at 80.01 219.71 0)
			(effects
				(font
					(size 1.27 1.27)
					(thickness 0.15)
				)
				(justify left bottom)
				(hide yes)
			)
		)
		(property "Author" "Antmicro"
			(at 77.47 219.71 0)
			(effects
				(font
					(size 1.27 1.27)
					(thickness 0.15)
				)
				(justify left bottom)
				(hide yes)
			)
		)
		(property "Val" "50R"
			(at 104.14 238.76 90)
			(effects
				(font
					(size 1.27 1.27)
					(thickness 0.15)
				)
				(justify right)
			)
		)
		(property "Tolerance" "1%"
			(at 95.25 219.71 0)
			(effects
				(font
					(size 1.27 1.27)
				)
				(justify left bottom)
				(hide yes)
			)
		)
		(property "Public" ""
			(at 74.93 219.71 0)
			(effects
				(font
					(size 1.27 1.27)
				)
				(justify left bottom)
				(hide yes)
			)
		)
		(pin "1"
		)
		(pin "2"
		)
		(instances
			(project "polarfire-som"
				(path ""
					(reference "R88")
					(unit 1)
				)
			)
		)
	)
	(symbol
		(lib_id "antmicroCapacitors0402:C_100n_0402")
		(at 55.88 227.33 90)
		(unit 1)
		(exclude_from_sim no)
		(in_bom yes)
		(on_board yes)
		(dnp no)
		(property "Reference" "C3"
			(at 58.42 223.52 90)
			(effects
				(font
					(size 1.27 1.27)
					(thickness 0.15)
				)
				(justify right)
			)
		)
		(property "Value" "C_100n_0402"
			(at 66.04 207.01 0)
			(effects
				(font
					(size 1.27 1.27)
					(thickness 0.15)
				)
				(justify left bottom)
				(hide yes)
			)
		)
		(property "Footprint" "antmicro-footprints:C_0402_1005Metric"
			(at 68.58 207.01 0)
			(effects
				(font
					(size 1.27 1.27)
					(thickness 0.15)
				)
				(justify left bottom)
				(hide yes)
			)
		)
		(property "Datasheet" "https://www.murata.com/products/productdetail?partno=GRM155R61H104KE14%23"
			(at 71.12 207.01 0)
			(effects
				(font
					(size 1.27 1.27)
					(thickness 0.15)
				)
				(justify left bottom)
				(hide yes)
			)
		)
		(property "Description" "SMD Multilayer Ceramic Capacitor, 0.1 µF, 50 V, 0402 [1005 Metric], ± 10%, X5R, GRM Series"
			(at 55.88 227.33 0)
			(effects
				(font
					(size 1.27 1.27)
				)
				(hide yes)
			)
		)
		(property "MPN" "GRM155R61H104KE14D"
			(at 73.66 207.01 0)
			(effects
				(font
					(size 1.27 1.27)
					(thickness 0.15)
				)
				(justify left bottom)
				(hide yes)
			)
		)
		(property "Manufacturer" "Murata"
			(at 76.2 207.01 0)
			(effects
				(font
					(size 1.27 1.27)
					(thickness 0.15)
				)
				(justify left bottom)
				(hide yes)
			)
		)
		(property "License" "Apache-2.0"
			(at 78.74 207.01 0)
			(effects
				(font
					(size 1.27 1.27)
					(thickness 0.15)
				)
				(justify left bottom)
				(hide yes)
			)
		)
		(property "Author" "Antmicro"
			(at 81.28 207.01 0)
			(effects
				(font
					(size 1.27 1.27)
					(thickness 0.15)
				)
				(justify left bottom)
				(hide yes)
			)
		)
		(property "Val" "100n"
			(at 63.5 226.06 90)
			(effects
				(font
					(size 1.27 1.27)
					(thickness 0.15)
				)
				(justify left bottom)
			)
		)
		(property "Voltage" "50V"
			(at 83.82 207.01 0)
			(effects
				(font
					(size 1.27 1.27)
				)
				(justify left bottom)
				(hide yes)
			)
		)
		(property "Dielectric" "X5R"
			(at 86.36 207.01 0)
			(effects
				(font
					(size 1.27 1.27)
				)
				(justify left bottom)
				(hide yes)
			)
		)
		(property "Public" ""
			(at 88.9 207.01 0)
			(effects
				(font
					(size 1.27 1.27)
				)
				(justify left bottom)
				(hide yes)
			)
		)
		(pin "1"
		)
		(pin "2"
		)
		(instances
			(project "polarfire-som"
				(path ""
					(reference "C3")
					(unit 1)
				)
			)
		)
	)
	(symbol
		(lib_id "antmicroCapacitors0402:C_100n_0402")
		(at 113.03 232.41 0)
		(unit 1)
		(exclude_from_sim no)
		(in_bom yes)
		(on_board yes)
		(dnp no)
		(property "Reference" "C53"
			(at 111.76 233.68 0)
			(effects
				(font
					(size 1.27 1.27)
					(thickness 0.15)
				)
			)
		)
		(property "Value" "C_100n_0402"
			(at 133.35 242.57 0)
			(effects
				(font
					(size 1.27 1.27)
					(thickness 0.15)
				)
				(justify left bottom)
				(hide yes)
			)
		)
		(property "Footprint" "antmicro-footprints:C_0402_1005Metric"
			(at 133.35 245.11 0)
			(effects
				(font
					(size 1.27 1.27)
					(thickness 0.15)
				)
				(justify left bottom)
				(hide yes)
			)
		)
		(property "Datasheet" "https://www.murata.com/products/productdetail?partno=GRM155R61H104KE14%23"
			(at 133.35 247.65 0)
			(effects
				(font
					(size 1.27 1.27)
					(thickness 0.15)
				)
				(justify left bottom)
				(hide yes)
			)
		)
		(property "Description" "SMD Multilayer Ceramic Capacitor, 0.1 µF, 50 V, 0402 [1005 Metric], ± 10%, X5R, GRM Series"
			(at 113.03 232.41 0)
			(effects
				(font
					(size 1.27 1.27)
				)
				(hide yes)
			)
		)
		(property "MPN" "GRM155R61H104KE14D"
			(at 133.35 250.19 0)
			(effects
				(font
					(size 1.27 1.27)
					(thickness 0.15)
				)
				(justify left bottom)
				(hide yes)
			)
		)
		(property "Manufacturer" "Murata"
			(at 133.35 252.73 0)
			(effects
				(font
					(size 1.27 1.27)
					(thickness 0.15)
				)
				(justify left bottom)
				(hide yes)
			)
		)
		(property "License" "Apache-2.0"
			(at 133.35 255.27 0)
			(effects
				(font
					(size 1.27 1.27)
					(thickness 0.15)
				)
				(justify left bottom)
				(hide yes)
			)
		)
		(property "Author" "Antmicro"
			(at 133.35 257.81 0)
			(effects
				(font
					(size 1.27 1.27)
					(thickness 0.15)
				)
				(justify left bottom)
				(hide yes)
			)
		)
		(property "Val" "100n"
			(at 116.84 233.68 0)
			(effects
				(font
					(size 1.27 1.27)
					(thickness 0.15)
				)
				(justify left)
			)
		)
		(property "Voltage" "50V"
			(at 133.35 260.35 0)
			(effects
				(font
					(size 1.27 1.27)
				)
				(justify left bottom)
				(hide yes)
			)
		)
		(property "Dielectric" "X5R"
			(at 133.35 262.89 0)
			(effects
				(font
					(size 1.27 1.27)
				)
				(justify left bottom)
				(hide yes)
			)
		)
		(property "Public" ""
			(at 133.35 265.43 0)
			(effects
				(font
					(size 1.27 1.27)
				)
				(justify left bottom)
				(hide yes)
			)
		)
		(pin "2"
		)
		(pin "1"
		)
		(instances
			(project "polarfire-som"
				(path ""
					(reference "C53")
					(unit 1)
				)
			)
		)
	)
	(symbol
		(lib_id "antmicroCapacitorsmisc:C_4x100nF_0508_1220Metric_array")
		(at 161.29 130.81 0)
		(unit 1)
		(exclude_from_sim no)
		(in_bom yes)
		(on_board yes)
		(dnp no)
		(property "Reference" "C172"
			(at 165.735 127.635 0)
			(effects
				(font
					(size 1.27 1.27)
					(thickness 0.15)
				)
			)
		)
		(property "Value" "C_4x100nF_0508_1220Metric_array"
			(at 176.53 139.7 0)
			(effects
				(font
					(size 1.27 1.27)
					(thickness 0.15)
				)
				(justify left bottom)
				(hide yes)
			)
		)
		(property "Footprint" "antmicro-footprints:C_Array_0508_1220Metric"
			(at 176.53 142.24 0)
			(effects
				(font
					(size 1.27 1.27)
					(thickness 0.15)
				)
				(justify left bottom)
				(hide yes)
			)
		)
		(property "Datasheet" "https://spicat.kyocera-avx.com/product/mlcc/chartview/W2A4YC104MAT2A/"
			(at 176.53 144.78 0)
			(effects
				(font
					(size 1.27 1.27)
					(thickness 0.15)
				)
				(justify left bottom)
				(hide yes)
			)
		)
		(property "Description" "4x0.1µF isolated capacitor array 16 V X7R 0508 (1220 Metric)"
			(at 161.29 130.81 0)
			(effects
				(font
					(size 1.27 1.27)
				)
				(hide yes)
			)
		)
		(property "MPN" "W2A4YC104MAT2A"
			(at 176.53 137.16 0)
			(effects
				(font
					(size 1.27 1.27)
					(thickness 0.15)
				)
				(justify left bottom)
				(hide yes)
			)
		)
		(property "Manufacturer" "KYOCERA AVX"
			(at 176.53 147.32 0)
			(effects
				(font
					(size 1.27 1.27)
					(thickness 0.15)
				)
				(justify left bottom)
				(hide yes)
			)
		)
		(property "Author" "Antmicro"
			(at 176.53 149.86 0)
			(effects
				(font
					(size 1.27 1.27)
					(thickness 0.15)
				)
				(justify left bottom)
				(hide yes)
			)
		)
		(property "License" "Apache-2.0"
			(at 176.53 152.4 0)
			(effects
				(font
					(size 1.27 1.27)
					(thickness 0.15)
				)
				(justify left bottom)
				(hide yes)
			)
		)
		(property "Val" "4x100nF"
			(at 165.735 140.97 0)
			(effects
				(font
					(size 1.27 1.27)
					(thickness 0.15)
				)
			)
		)
		(property "Voltage" "16V"
			(at 176.53 157.48 0)
			(effects
				(font
					(size 1.27 1.27)
				)
				(justify left bottom)
				(hide yes)
			)
		)
		(property "Dielectric" "X7R"
			(at 176.53 154.94 0)
			(effects
				(font
					(size 1.27 1.27)
				)
				(justify left bottom)
				(hide yes)
			)
		)
		(pin "7"
		)
		(pin "3"
		)
		(pin "8"
		)
		(pin "4"
		)
		(pin "2"
		)
		(pin "1"
		)
		(pin "6"
		)
		(pin "5"
		)
		(instances
			(project "polarfire-som"
				(path ""
					(reference "C172")
					(unit 1)
				)
			)
		)
	)
	(symbol
		(lib_id "antmicroResistors0402:R_50R_0402")
		(at 107.95 240.03 90)
		(unit 1)
		(exclude_from_sim no)
		(in_bom yes)
		(on_board yes)
		(dnp no)
		(property "Reference" "R89"
			(at 109.22 236.22 90)
			(effects
				(font
					(size 1.27 1.27)
					(thickness 0.15)
				)
				(justify right)
			)
		)
		(property "Value" "R_50R_0402"
			(at 120.65 219.71 0)
			(effects
				(font
					(size 1.27 1.27)
					(thickness 0.15)
				)
				(justify left bottom)
				(hide yes)
			)
		)
		(property "Footprint" "antmicro-footprints:R_0402_1005Metric"
			(at 123.19 219.71 0)
			(effects
				(font
					(size 1.27 1.27)
					(thickness 0.15)
				)
				(justify left bottom)
				(hide yes)
			)
		)
		(property "Datasheet" "https://www.bourns.com/docs/product-datasheets/cr.pdf"
			(at 125.73 219.71 0)
			(effects
				(font
					(size 1.27 1.27)
					(thickness 0.15)
				)
				(justify left bottom)
				(hide yes)
			)
		)
		(property "Description" "SMD Chip Resistor"
			(at 107.95 240.03 0)
			(effects
				(font
					(size 1.27 1.27)
				)
				(hide yes)
			)
		)
		(property "MPN" "CR0402-FX-50R0GLF"
			(at 128.27 219.71 0)
			(effects
				(font
					(size 1.27 1.27)
					(thickness 0.15)
				)
				(justify left bottom)
				(hide yes)
			)
		)
		(property "Manufacturer" "Bourns"
			(at 130.81 219.71 0)
			(effects
				(font
					(size 1.27 1.27)
					(thickness 0.15)
				)
				(justify left bottom)
				(hide yes)
			)
		)
		(property "License" "Apache-2.0"
			(at 133.35 219.71 0)
			(effects
				(font
					(size 1.27 1.27)
					(thickness 0.15)
				)
				(justify left bottom)
				(hide yes)
			)
		)
		(property "Author" "Antmicro"
			(at 135.89 219.71 0)
			(effects
				(font
					(size 1.27 1.27)
					(thickness 0.15)
				)
				(justify left bottom)
				(hide yes)
			)
		)
		(property "Val" "50R"
			(at 109.22 238.76 90)
			(effects
				(font
					(size 1.27 1.27)
					(thickness 0.15)
				)
				(justify right)
			)
		)
		(property "Tolerance" "1%"
			(at 118.11 219.71 0)
			(effects
				(font
					(size 1.27 1.27)
				)
				(justify left bottom)
				(hide yes)
			)
		)
		(property "Public" ""
			(at 138.43 219.71 0)
			(effects
				(font
					(size 1.27 1.27)
				)
				(justify left bottom)
				(hide yes)
			)
		)
		(pin "1"
		)
		(pin "2"
		)
		(instances
			(project "polarfire-som"
				(path ""
					(reference "R89")
					(unit 1)
				)
			)
		)
	)
	(symbol
		(lib_id "antmicroCapacitorsmisc:C_4x100nF_0508_1220Metric_array")
		(at 161.29 115.57 0)
		(unit 1)
		(exclude_from_sim no)
		(in_bom yes)
		(on_board yes)
		(dnp no)
		(property "Reference" "C171"
			(at 165.735 113.03 0)
			(effects
				(font
					(size 1.27 1.27)
					(thickness 0.15)
				)
			)
		)
		(property "Value" "C_4x100nF_0508_1220Metric_array"
			(at 176.53 124.46 0)
			(effects
				(font
					(size 1.27 1.27)
					(thickness 0.15)
				)
				(justify left bottom)
				(hide yes)
			)
		)
		(property "Footprint" "antmicro-footprints:C_Array_0508_1220Metric"
			(at 176.53 127 0)
			(effects
				(font
					(size 1.27 1.27)
					(thickness 0.15)
				)
				(justify left bottom)
				(hide yes)
			)
		)
		(property "Datasheet" "https://spicat.kyocera-avx.com/product/mlcc/chartview/W2A4YC104MAT2A/"
			(at 176.53 129.54 0)
			(effects
				(font
					(size 1.27 1.27)
					(thickness 0.15)
				)
				(justify left bottom)
				(hide yes)
			)
		)
		(property "Description" "4x0.1µF isolated capacitor array 16 V X7R 0508 (1220 Metric)"
			(at 161.29 115.57 0)
			(effects
				(font
					(size 1.27 1.27)
				)
				(hide yes)
			)
		)
		(property "MPN" "W2A4YC104MAT2A"
			(at 176.53 121.92 0)
			(effects
				(font
					(size 1.27 1.27)
					(thickness 0.15)
				)
				(justify left bottom)
				(hide yes)
			)
		)
		(property "Manufacturer" "KYOCERA AVX"
			(at 176.53 132.08 0)
			(effects
				(font
					(size 1.27 1.27)
					(thickness 0.15)
				)
				(justify left bottom)
				(hide yes)
			)
		)
		(property "Author" "Antmicro"
			(at 176.53 134.62 0)
			(effects
				(font
					(size 1.27 1.27)
					(thickness 0.15)
				)
				(justify left bottom)
				(hide yes)
			)
		)
		(property "License" "Apache-2.0"
			(at 176.53 137.16 0)
			(effects
				(font
					(size 1.27 1.27)
					(thickness 0.15)
				)
				(justify left bottom)
				(hide yes)
			)
		)
		(property "Val" "4x100nF"
			(at 165.735 125.73 0)
			(effects
				(font
					(size 1.27 1.27)
					(thickness 0.15)
				)
			)
		)
		(property "Voltage" "16V"
			(at 176.53 142.24 0)
			(effects
				(font
					(size 1.27 1.27)
				)
				(justify left bottom)
				(hide yes)
			)
		)
		(property "Dielectric" "X7R"
			(at 176.53 139.7 0)
			(effects
				(font
					(size 1.27 1.27)
				)
				(justify left bottom)
				(hide yes)
			)
		)
		(pin "7"
		)
		(pin "3"
		)
		(pin "8"
		)
		(pin "4"
		)
		(pin "2"
		)
		(pin "1"
		)
		(pin "6"
		)
		(pin "5"
		)
		(instances
			(project "polarfire-som"
				(path ""
					(reference "C171")
					(unit 1)
				)
			)
		)
	)
	(symbol
		(lib_id "antmicroFPGAChips:MPFS250T-FCVG484E")
		(at 187.96 114.3 0)
		(unit 8)
		(exclude_from_sim no)
		(in_bom yes)
		(on_board yes)
		(dnp no)
		(fields_autoplaced yes)
		(property "Reference" "U1"
			(at 213.36 104.14 0)
			(effects
				(font
					(size 1.27 1.27)
					(thickness 0.15)
				)
			)
		)
		(property "Value" "MPFS250T-FCVG484"
			(at 293.37 119.38 0)
			(effects
				(font
					(size 1.27 1.27)
					(thickness 0.15)
				)
				(justify left bottom)
				(hide yes)
			)
		)
		(property "Footprint" "antmicro-footprints:BGA-484_19x19mm_Layout22x22_P0.8mm_FCVG484"
			(at 293.37 121.92 0)
			(effects
				(font
					(size 1.27 1.27)
					(thickness 0.15)
				)
				(justify left bottom)
				(hide yes)
			)
		)
		(property "Datasheet" "https://ww1.microchip.com/downloads/aemDocuments/documents/FPGA/ProductDocuments/DataSheets/PolarFire-SoC-Datasheet-DS00004248.pdf"
			(at 293.37 124.46 0)
			(effects
				(font
					(size 1.27 1.27)
					(thickness 0.15)
				)
				(justify left bottom)
				(hide yes)
			)
		)
		(property "Description" "RISC-V System On Chip (SOC) IC PolarFire® FPGA - 254K Logic Modules 484-FCBGA (19x19)"
			(at 293.37 134.62 0)
			(effects
				(font
					(size 1.27 1.27)
				)
				(justify left bottom)
				(hide yes)
			)
		)
		(property "MPN" "MPFS250T-FCVG484E"
			(at 213.36 106.68 0)
			(effects
				(font
					(size 1.27 1.27)
					(thickness 0.15)
				)
			)
		)
		(property "Manufacturer" "Microchip Technology"
			(at 293.37 127 0)
			(effects
				(font
					(size 1.27 1.27)
					(thickness 0.15)
				)
				(justify left bottom)
				(hide yes)
			)
		)
		(property "VSD_class" "MPFS250T"
			(at 292.1 132.08 0)
			(effects
				(font
					(size 1.27 1.27)
					(thickness 0.15)
				)
				(justify left bottom)
				(hide yes)
			)
		)
		(property "Author" "Antmicro"
			(at 293.37 129.54 0)
			(effects
				(font
					(size 1.27 1.27)
					(thickness 0.15)
				)
				(justify left bottom)
				(hide yes)
			)
		)
		(property "License" "Apache-2.0"
			(at 293.37 132.08 0)
			(effects
				(font
					(size 1.27 1.27)
					(thickness 0.15)
				)
				(justify left bottom)
				(hide yes)
			)
		)
		(pin "AA12"
		)
		(pin "AA13"
		)
		(pin "AA15"
		)
		(pin "AA16"
		)
		(pin "AA17"
		)
		(pin "AA18"
		)
		(pin "AA20"
		)
		(pin "AA21"
		)
		(pin "AA22"
		)
		(pin "AB12"
		)
		(pin "AB13"
		)
		(pin "AB14"
		)
		(pin "AB15"
		)
		(pin "AB17"
		)
		(pin "AB18"
		)
		(pin "AB19"
		)
		(pin "AB20"
		)
		(pin "AB21"
		)
		(pin "R12"
		)
		(pin "R14"
		)
		(pin "R15"
		)
		(pin "R16"
		)
		(pin "T12"
		)
		(pin "T13"
		)
		(pin "T15"
		)
		(pin "T16"
		)
		(pin "T17"
		)
		(pin "U12"
		)
		(pin "U13"
		)
		(pin "U14"
		)
		(pin "U15"
		)
		(pin "U17"
		)
		(pin "U18"
		)
		(pin "U19"
		)
		(pin "V12"
		)
		(pin "V14"
		)
		(pin "V15"
		)
		(pin "V16"
		)
		(pin "V17"
		)
		(pin "V19"
		)
		(pin "V20"
		)
		(pin "V21"
		)
		(pin "V22"
		)
		(pin "W12"
		)
		(pin "W13"
		)
		(pin "W14"
		)
		(pin "W16"
		)
		(pin "W17"
		)
		(pin "W18"
		)
		(pin "W19"
		)
		(pin "W21"
		)
		(pin "W22"
		)
		(pin "Y13"
		)
		(pin "Y14"
		)
		(pin "Y15"
		)
		(pin "Y16"
		)
		(pin "Y18"
		)
		(pin "Y19"
		)
		(pin "Y20"
		)
		(pin "Y21"
		)
		(pin "A10"
		)
		(pin "A11"
		)
		(pin "A12"
		)
		(pin "A13"
		)
		(pin "A15"
		)
		(pin "A16"
		)
		(pin "A17"
		)
		(pin "A18"
		)
		(pin "A20"
		)
		(pin "A21"
		)
		(pin "A5"
		)
		(pin "A6"
		)
		(pin "A7"
		)
		(pin "A8"
		)
		(pin "B10"
		)
		(pin "B12"
		)
		(pin "B13"
		)
		(pin "B14"
		)
		(pin "B15"
		)
		(pin "B17"
		)
		(pin "B18"
		)
		(pin "B19"
		)
		(pin "B20"
		)
		(pin "B21"
		)
		(pin "B22"
		)
		(pin "B4"
		)
		(pin "B5"
		)
		(pin "B7"
		)
		(pin "B8"
		)
		(pin "B9"
		)
		(pin "C10"
		)
		(pin "C11"
		)
		(pin "C12"
		)
		(pin "C14"
		)
		(pin "C15"
		)
		(pin "C16"
		)
		(pin "C17"
		)
		(pin "C19"
		)
		(pin "C20"
		)
		(pin "C22"
		)
		(pin "C4"
		)
		(pin "C5"
		)
		(pin "C6"
		)
		(pin "C7"
		)
		(pin "C9"
		)
		(pin "D11"
		)
		(pin "D12"
		)
		(pin "D13"
		)
		(pin "D14"
		)
		(pin "D16"
		)
		(pin "D17"
		)
		(pin "D18"
		)
		(pin "D19"
		)
		(pin "D20"
		)
		(pin "D21"
		)
		(pin "D22"
		)
		(pin "D6"
		)
		(pin "D7"
		)
		(pin "D8"
		)
		(pin "D9"
		)
		(pin "E10"
		)
		(pin "E11"
		)
		(pin "E13"
		)
		(pin "E14"
		)
		(pin "E15"
		)
		(pin "E16"
		)
		(pin "E18"
		)
		(pin "E19"
		)
		(pin "F10"
		)
		(pin "F11"
		)
		(pin "F12"
		)
		(pin "F13"
		)
		(pin "F15"
		)
		(pin "F16"
		)
		(pin "F17"
		)
		(pin "G12"
		)
		(pin "G13"
		)
		(pin "G14"
		)
		(pin "G15"
		)
		(pin "G17"
		)
		(pin "H12"
		)
		(pin "H13"
		)
		(pin "H15"
		)
		(pin "H17"
		)
		(pin "A2"
		)
		(pin "A3"
		)
		(pin "B1"
		)
		(pin "B2"
		)
		(pin "B3"
		)
		(pin "C1"
		)
		(pin "C2"
		)
		(pin "D1"
		)
		(pin "D2"
		)
		(pin "D3"
		)
		(pin "D4"
		)
		(pin "E1"
		)
		(pin "E3"
		)
		(pin "E4"
		)
		(pin "E5"
		)
		(pin "F1"
		)
		(pin "F2"
		)
		(pin "F3"
		)
		(pin "F5"
		)
		(pin "F6"
		)
		(pin "G2"
		)
		(pin "G3"
		)
		(pin "G4"
		)
		(pin "G5"
		)
		(pin "E6"
		)
		(pin "E8"
		)
		(pin "E9"
		)
		(pin "F7"
		)
		(pin "F8"
		)
		(pin "G10"
		)
		(pin "G7"
		)
		(pin "G8"
		)
		(pin "G9"
		)
		(pin "H10"
		)
		(pin "H11"
		)
		(pin "H7"
		)
		(pin "H9"
		)
		(pin "H1"
		)
		(pin "H2"
		)
		(pin "H4"
		)
		(pin "H5"
		)
		(pin "H6"
		)
		(pin "J1"
		)
		(pin "J2"
		)
		(pin "J3"
		)
		(pin "J4"
		)
		(pin "J6"
		)
		(pin "J7"
		)
		(pin "K3"
		)
		(pin "K4"
		)
		(pin "K5"
		)
		(pin "K6"
		)
		(pin "K7"
		)
		(pin "L5"
		)
		(pin "L6"
		)
		(pin "L7"
		)
		(pin "L8"
		)
		(pin "M7"
		)
		(pin "N6"
		)
		(pin "N7"
		)
		(pin "N8"
		)
		(pin "AA1"
		)
		(pin "AA10"
		)
		(pin "AA11"
		)
		(pin "AA2"
		)
		(pin "AA3"
		)
		(pin "AA5"
		)
		(pin "AA6"
		)
		(pin "AA7"
		)
		(pin "AA8"
		)
		(pin "AB10"
		)
		(pin "AB2"
		)
		(pin "AB3"
		)
		(pin "AB4"
		)
		(pin "AB5"
		)
		(pin "AB7"
		)
		(pin "AB8"
		)
		(pin "AB9"
		)
		(pin "K1"
		)
		(pin "L1"
		)
		(pin "L2"
		)
		(pin "L3"
		)
		(pin "M2"
		)
		(pin "M3"
		)
		(pin "M4"
		)
		(pin "M5"
		)
		(pin "N1"
		)
		(pin "N2"
		)
		(pin "N4"
		)
		(pin "N5"
		)
		(pin "P1"
		)
		(pin "P2"
		)
		(pin "P3"
		)
		(pin "P4"
		)
		(pin "P6"
		)
		(pin "P7"
		)
		(pin "P8"
		)
		(pin "R1"
		)
		(pin "R10"
		)
		(pin "R11"
		)
		(pin "R3"
		)
		(pin "R4"
		)
		(pin "R5"
		)
		(pin "R6"
		)
		(pin "R8"
		)
		(pin "T1"
		)
		(pin "T10"
		)
		(pin "T11"
		)
		(pin "T2"
		)
		(pin "T3"
		)
		(pin "T5"
		)
		(pin "T6"
		)
		(pin "T7"
		)
		(pin "T8"
		)
		(pin "U10"
		)
		(pin "U2"
		)
		(pin "U3"
		)
		(pin "U4"
		)
		(pin "U5"
		)
		(pin "U7"
		)
		(pin "U8"
		)
		(pin "U9"
		)
		(pin "V1"
		)
		(pin "V10"
		)
		(pin "V11"
		)
		(pin "V2"
		)
		(pin "V4"
		)
		(pin "V5"
		)
		(pin "V6"
		)
		(pin "V7"
		)
		(pin "V9"
		)
		(pin "W1"
		)
		(pin "W11"
		)
		(pin "W2"
		)
		(pin "W3"
		)
		(pin "W4"
		)
		(pin "W6"
		)
		(pin "W7"
		)
		(pin "W8"
		)
		(pin "W9"
		)
		(pin "Y1"
		)
		(pin "Y10"
		)
		(pin "Y11"
		)
		(pin "Y3"
		)
		(pin "Y4"
		)
		(pin "Y5"
		)
		(pin "Y6"
		)
		(pin "Y8"
		)
		(pin "Y9"
		)
		(pin "F21"
		)
		(pin "F22"
		)
		(pin "G19"
		)
		(pin "G20"
		)
		(pin "H21"
		)
		(pin "H22"
		)
		(pin "J19"
		)
		(pin "J20"
		)
		(pin "K21"
		)
		(pin "K22"
		)
		(pin "L19"
		)
		(pin "L20"
		)
		(pin "M21"
		)
		(pin "M22"
		)
		(pin "N19"
		)
		(pin "N20"
		)
		(pin "P21"
		)
		(pin "P22"
		)
		(pin "R19"
		)
		(pin "R20"
		)
		(pin "T21"
		)
		(pin "T22"
		)
		(pin "A1"
		)
		(pin "A14"
		)
		(pin "A19"
		)
		(pin "A22"
		)
		(pin "A4"
		)
		(pin "A9"
		)
		(pin "AA14"
		)
		(pin "AA19"
		)
		(pin "AA4"
		)
		(pin "AA9"
		)
		(pin "AB1"
		)
		(pin "AB11"
		)
		(pin "AB16"
		)
		(pin "AB22"
		)
		(pin "AB6"
		)
		(pin "B11"
		)
		(pin "B16"
		)
		(pin "B6"
		)
		(pin "C13"
		)
		(pin "C18"
		)
		(pin "C21"
		)
		(pin "C3"
		)
		(pin "C8"
		)
		(pin "D10"
		)
		(pin "D15"
		)
		(pin "D5"
		)
		(pin "E12"
		)
		(pin "E17"
		)
		(pin "E2"
		)
		(pin "E20"
		)
		(pin "E21"
		)
		(pin "E22"
		)
		(pin "E7"
		)
		(pin "F14"
		)
		(pin "F18"
		)
		(pin "F19"
		)
		(pin "F20"
		)
		(pin "F4"
		)
		(pin "F9"
		)
		(pin "G1"
		)
		(pin "G11"
		)
		(pin "G16"
		)
		(pin "G18"
		)
		(pin "G21"
		)
		(pin "G22"
		)
		(pin "G6"
		)
		(pin "H14"
		)
		(pin "H16"
		)
		(pin "H18"
		)
		(pin "H19"
		)
		(pin "H20"
		)
		(pin "H3"
		)
		(pin "H8"
		)
		(pin "J10"
		)
		(pin "J11"
		)
		(pin "J12"
		)
		(pin "J13"
		)
		(pin "J14"
		)
		(pin "J15"
		)
		(pin "J16"
		)
		(pin "J17"
		)
		(pin "J18"
		)
		(pin "J21"
		)
		(pin "J22"
		)
		(pin "J5"
		)
		(pin "J8"
		)
		(pin "J9"
		)
		(pin "K10"
		)
		(pin "K11"
		)
		(pin "K12"
		)
		(pin "K13"
		)
		(pin "K14"
		)
		(pin "K15"
		)
		(pin "K16"
		)
		(pin "K17"
		)
		(pin "K18"
		)
		(pin "K19"
		)
		(pin "K2"
		)
		(pin "K20"
		)
		(pin "K8"
		)
		(pin "K9"
		)
		(pin "L10"
		)
		(pin "L11"
		)
		(pin "L12"
		)
		(pin "L13"
		)
		(pin "L14"
		)
		(pin "L15"
		)
		(pin "L16"
		)
		(pin "L17"
		)
		(pin "L18"
		)
		(pin "L21"
		)
		(pin "L22"
		)
		(pin "L4"
		)
		(pin "L9"
		)
		(pin "M1"
		)
		(pin "M10"
		)
		(pin "M11"
		)
		(pin "M12"
		)
		(pin "M13"
		)
		(pin "M14"
		)
		(pin "M15"
		)
		(pin "M16"
		)
		(pin "M17"
		)
		(pin "M18"
		)
		(pin "M19"
		)
		(pin "M20"
		)
		(pin "M6"
		)
		(pin "M8"
		)
		(pin "M9"
		)
		(pin "N10"
		)
		(pin "N11"
		)
		(pin "N12"
		)
		(pin "N13"
		)
		(pin "N14"
		)
		(pin "N15"
		)
		(pin "N16"
		)
		(pin "N17"
		)
		(pin "N18"
		)
		(pin "N21"
		)
		(pin "N22"
		)
		(pin "N3"
		)
		(pin "N9"
		)
		(pin "P10"
		)
		(pin "P11"
		)
		(pin "P12"
		)
		(pin "P13"
		)
		(pin "P14"
		)
		(pin "P15"
		)
		(pin "P16"
		)
		(pin "P17"
		)
		(pin "P18"
		)
		(pin "P19"
		)
		(pin "P20"
		)
		(pin "P5"
		)
		(pin "P9"
		)
		(pin "R13"
		)
		(pin "R17"
		)
		(pin "R18"
		)
		(pin "R2"
		)
		(pin "R21"
		)
		(pin "R22"
		)
		(pin "R7"
		)
		(pin "R9"
		)
		(pin "T14"
		)
		(pin "T18"
		)
		(pin "T19"
		)
		(pin "T20"
		)
		(pin "T4"
		)
		(pin "T9"
		)
		(pin "U1"
		)
		(pin "U11"
		)
		(pin "U16"
		)
		(pin "U20"
		)
		(pin "U21"
		)
		(pin "U22"
		)
		(pin "U6"
		)
		(pin "V13"
		)
		(pin "V18"
		)
		(pin "V3"
		)
		(pin "V8"
		)
		(pin "W10"
		)
		(pin "W15"
		)
		(pin "W20"
		)
		(pin "W5"
		)
		(pin "Y12"
		)
		(pin "Y17"
		)
		(pin "Y2"
		)
		(pin "Y22"
		)
		(pin "Y7"
		)
		(instances
			(project "polarfire-som"
				(path ""
					(reference "U1")
					(unit 8)
				)
			)
		)
	)
	(symbol
		(lib_id "antmicroClockTimingRealTimeClocks:DSC557-0343FI1")
		(at 74.93 220.98 0)
		(unit 1)
		(exclude_from_sim no)
		(in_bom yes)
		(on_board yes)
		(dnp no)
		(property "Reference" "U17"
			(at 87.63 210.82 0)
			(effects
				(font
					(size 1.27 1.27)
					(thickness 0.15)
				)
			)
		)
		(property "Value" "DSC557-0343FI1"
			(at 87.63 213.36 0)
			(effects
				(font
					(size 1.27 1.27)
					(thickness 0.15)
				)
			)
		)
		(property "Footprint" "antmicro-footprints:VQFN-14-1EP_3.2x2.5mm_P0.5mm_Layout4x3"
			(at 120.65 233.68 0)
			(effects
				(font
					(size 1.27 1.27)
					(thickness 0.15)
				)
				(justify left bottom)
				(hide yes)
			)
		)
		(property "Datasheet" "https://ww1.microchip.com/downloads/aemDocuments/documents/TCG/ProductDocuments/DataSheets/DSC557-03-04-05-Multiple-Output-MEMS-PCIe-Gen1-2-3-4-Clock-Generators-DS20006691.pdf"
			(at 120.65 236.22 0)
			(effects
				(font
					(size 1.27 1.27)
					(thickness 0.15)
				)
				(justify left bottom)
				(hide yes)
			)
		)
		(property "Description" "Two output PCIe Clock Generator"
			(at 74.93 220.98 0)
			(effects
				(font
					(size 1.27 1.27)
				)
				(hide yes)
			)
		)
		(property "Manufacturer" "Microchip Technology"
			(at 120.65 238.76 0)
			(effects
				(font
					(size 1.27 1.27)
					(thickness 0.15)
				)
				(justify left bottom)
				(hide yes)
			)
		)
		(property "MPN" "DSC557-0343FI1"
			(at 120.65 241.3 0)
			(effects
				(font
					(size 1.27 1.27)
					(thickness 0.15)
				)
				(justify left bottom)
				(hide yes)
			)
		)
		(property "Author" "Antmicro"
			(at 120.65 243.84 0)
			(effects
				(font
					(size 1.27 1.27)
					(thickness 0.15)
				)
				(justify left bottom)
				(hide yes)
			)
		)
		(property "License" "Apache-2.0"
			(at 120.65 246.38 0)
			(effects
				(font
					(size 1.27 1.27)
					(thickness 0.15)
				)
				(justify left bottom)
				(hide yes)
			)
		)
		(property "Val" "100 MHz"
			(at 87.63 215.9 0)
			(effects
				(font
					(size 1.27 1.27)
				)
			)
		)
		(pin "13"
		)
		(pin "10"
		)
		(pin "6"
		)
		(pin "11"
		)
		(pin "9"
		)
		(pin "15"
		)
		(pin "1"
		)
		(pin "2"
		)
		(pin "7"
		)
		(pin "14"
		)
		(pin "12"
		)
		(pin "4"
		)
		(pin "5"
		)
		(pin "3"
		)
		(pin "8"
		)
		(instances
			(project "polarfire-som"
				(path ""
					(reference "U17")
					(unit 1)
				)
			)
		)
	)
	(symbol
		(lib_id "antmicropower:GND")
		(at 55.88 232.41 0)
		(unit 1)
		(exclude_from_sim no)
		(in_bom yes)
		(on_board yes)
		(dnp no)
		(property "Reference" "#PWR0171"
			(at 64.77 234.95 0)
			(effects
				(font
					(size 1.27 1.27)
					(thickness 0.15)
				)
				(justify left bottom)
				(hide yes)
			)
		)
		(property "Value" "GND"
			(at 55.88 236.22 0)
			(effects
				(font
					(size 1.27 1.27)
					(thickness 0.15)
				)
			)
		)
		(property "Footprint" ""
			(at 64.77 240.03 0)
			(effects
				(font
					(size 1.27 1.27)
					(thickness 0.15)
				)
				(justify left bottom)
				(hide yes)
			)
		)
		(property "Datasheet" ""
			(at 64.77 245.11 0)
			(effects
				(font
					(size 1.27 1.27)
					(thickness 0.15)
				)
				(justify left bottom)
				(hide yes)
			)
		)
		(property "Description" ""
			(at 55.88 232.41 0)
			(effects
				(font
					(size 1.27 1.27)
				)
				(hide yes)
			)
		)
		(property "Author" "Antmicro"
			(at 64.77 240.03 0)
			(effects
				(font
					(size 1.27 1.27)
					(thickness 0.15)
				)
				(justify left bottom)
				(hide yes)
			)
		)
		(property "License" "Apache-2.0"
			(at 64.77 242.57 0)
			(effects
				(font
					(size 1.27 1.27)
					(thickness 0.15)
				)
				(justify left bottom)
				(hide yes)
			)
		)
		(pin "1"
		)
		(instances
			(project "polarfire-som"
				(path ""
					(reference "#PWR0171")
					(unit 1)
				)
			)
		)
	)
	(symbol
		(lib_id "antmicroCapacitors0402:C_100n_0402")
		(at 115.57 229.87 0)
		(mirror x)
		(unit 1)
		(exclude_from_sim no)
		(in_bom yes)
		(on_board yes)
		(dnp no)
		(property "Reference" "C68"
			(at 114.3 228.6 0)
			(effects
				(font
					(size 1.27 1.27)
					(thickness 0.15)
				)
			)
		)
		(property "Value" "C_100n_0402"
			(at 135.89 219.71 0)
			(effects
				(font
					(size 1.27 1.27)
					(thickness 0.15)
				)
				(justify left bottom)
				(hide yes)
			)
		)
		(property "Footprint" "antmicro-footprints:C_0402_1005Metric"
			(at 135.89 217.17 0)
			(effects
				(font
					(size 1.27 1.27)
					(thickness 0.15)
				)
				(justify left bottom)
				(hide yes)
			)
		)
		(property "Datasheet" "https://www.murata.com/products/productdetail?partno=GRM155R61H104KE14%23"
			(at 135.89 214.63 0)
			(effects
				(font
					(size 1.27 1.27)
					(thickness 0.15)
				)
				(justify left bottom)
				(hide yes)
			)
		)
		(property "Description" "SMD Multilayer Ceramic Capacitor, 0.1 µF, 50 V, 0402 [1005 Metric], ± 10%, X5R, GRM Series"
			(at 115.57 229.87 0)
			(effects
				(font
					(size 1.27 1.27)
				)
				(hide yes)
			)
		)
		(property "MPN" "GRM155R61H104KE14D"
			(at 135.89 212.09 0)
			(effects
				(font
					(size 1.27 1.27)
					(thickness 0.15)
				)
				(justify left bottom)
				(hide yes)
			)
		)
		(property "Manufacturer" "Murata"
			(at 135.89 209.55 0)
			(effects
				(font
					(size 1.27 1.27)
					(thickness 0.15)
				)
				(justify left bottom)
				(hide yes)
			)
		)
		(property "License" "Apache-2.0"
			(at 135.89 207.01 0)
			(effects
				(font
					(size 1.27 1.27)
					(thickness 0.15)
				)
				(justify left bottom)
				(hide yes)
			)
		)
		(property "Author" "Antmicro"
			(at 135.89 204.47 0)
			(effects
				(font
					(size 1.27 1.27)
					(thickness 0.15)
				)
				(justify left bottom)
				(hide yes)
			)
		)
		(property "Val" "100n"
			(at 119.38 228.6 0)
			(effects
				(font
					(size 1.27 1.27)
					(thickness 0.15)
				)
				(justify left)
			)
		)
		(property "Voltage" "50V"
			(at 135.89 201.93 0)
			(effects
				(font
					(size 1.27 1.27)
				)
				(justify left bottom)
				(hide yes)
			)
		)
		(property "Dielectric" "X5R"
			(at 135.89 199.39 0)
			(effects
				(font
					(size 1.27 1.27)
				)
				(justify left bottom)
				(hide yes)
			)
		)
		(property "Public" ""
			(at 135.89 196.85 0)
			(effects
				(font
					(size 1.27 1.27)
				)
				(justify left bottom)
				(hide yes)
			)
		)
		(pin "2"
		)
		(pin "1"
		)
		(instances
			(project "polarfire-som"
				(path ""
					(reference "C68")
					(unit 1)
				)
			)
		)
	)
)
